(kicad_sch
	(version 20250114)
	(generator "eeschema")
	(generator_version "9.0")
	(paper "A3")
	(title_block
		(title "Kintex 410T devboard")
		(date "2024-04-03")
		(rev "1.1.2")
	)
	(no_connect
		(at 172.72 151.13)
	)
	(no_connect
		(at 172.72 199.39)
	)
	(no_connect
		(at 172.72 175.26)
	)
	(no_connect
		(at 172.72 170.18)
	)
	(no_connect
		(at 220.98 161.29)
	)
	(no_connect
		(at 172.72 161.29)
	)
	(no_connect
		(at 220.98 172.72)
	)
	(no_connect
		(at 220.98 151.13)
	)
	(no_connect
		(at 220.98 199.39)
	)
	(no_connect
		(at 220.98 187.96)
	)
	(no_connect
		(at 172.72 153.67)
	)
	(no_connect
		(at 172.72 177.8)
	)
	(no_connect
		(at 220.98 148.59)
	)
	(no_connect
		(at 220.98 177.8)
	)
	(no_connect
		(at 220.98 196.85)
	)
	(no_connect
		(at 172.72 185.42)
	)
	(no_connect
		(at 220.98 191.77)
	)
	(no_connect
		(at 172.72 182.88)
	)
	(no_connect
		(at 220.98 163.83)
	)
	(no_connect
		(at 172.72 191.77)
	)
	(no_connect
		(at 172.72 187.96)
	)
	(no_connect
		(at 172.72 166.37)
	)
	(no_connect
		(at 172.72 172.72)
	)
	(no_connect
		(at 220.98 158.75)
	)
	(no_connect
		(at 172.72 148.59)
	)
	(no_connect
		(at 220.98 194.31)
	)
	(no_connect
		(at 172.72 163.83)
	)
	(no_connect
		(at 220.98 175.26)
	)
	(no_connect
		(at 220.98 180.34)
	)
	(no_connect
		(at 220.98 166.37)
	)
	(no_connect
		(at 172.72 156.21)
	)
	(no_connect
		(at 220.98 185.42)
	)
	(no_connect
		(at 172.72 194.31)
	)
	(no_connect
		(at 220.98 156.21)
	)
	(no_connect
		(at 220.98 182.88)
	)
	(no_connect
		(at 220.98 170.18)
	)
	(no_connect
		(at 172.72 196.85)
	)
	(no_connect
		(at 172.72 180.34)
	)
	(no_connect
		(at 172.72 158.75)
	)
	(no_connect
		(at 220.98 153.67)
	)
	(bus_entry
		(at 243.84 121.92)
		(size 1.27 -1.27)
		(stroke
			(width 0)
			(type default)
		)
	)
	(bus_entry
		(at 149.86 129.54)
		(size -1.27 -1.27)
		(stroke
			(width 0)
			(type default)
		)
	)
	(bus_entry
		(at 243.84 93.98)
		(size 1.27 -1.27)
		(stroke
			(width 0)
			(type default)
		)
	)
	(bus_entry
		(at 149.86 86.36)
		(size -1.27 -1.27)
		(stroke
			(width 0)
			(type default)
		)
	)
	(bus_entry
		(at 149.86 105.41)
		(size -1.27 -1.27)
		(stroke
			(width 0)
			(type default)
		)
	)
	(bus_entry
		(at 149.86 110.49)
		(size -1.27 -1.27)
		(stroke
			(width 0)
			(type default)
		)
	)
	(bus_entry
		(at 149.86 83.82)
		(size -1.27 -1.27)
		(stroke
			(width 0)
			(type default)
		)
	)
	(bus_entry
		(at 243.84 81.28)
		(size 1.27 -1.27)
		(stroke
			(width 0)
			(type default)
		)
	)
	(bus_entry
		(at 149.86 127)
		(size -1.27 -1.27)
		(stroke
			(width 0)
			(type default)
		)
	)
	(bus_entry
		(at 149.86 88.9)
		(size -1.27 -1.27)
		(stroke
			(width 0)
			(type default)
		)
	)
	(bus_entry
		(at 243.84 78.74)
		(size 1.27 -1.27)
		(stroke
			(width 0)
			(type default)
		)
	)
	(bus_entry
		(at 243.84 118.11)
		(size 1.27 -1.27)
		(stroke
			(width 0)
			(type default)
		)
	)
	(bus_entry
		(at 243.84 100.33)
		(size 1.27 -1.27)
		(stroke
			(width 0)
			(type default)
		)
	)
	(bus_entry
		(at 243.84 110.49)
		(size 1.27 -1.27)
		(stroke
			(width 0)
			(type default)
		)
	)
	(bus_entry
		(at 149.86 118.11)
		(size -1.27 -1.27)
		(stroke
			(width 0)
			(type default)
		)
	)
	(bus_entry
		(at 243.84 105.41)
		(size 1.27 -1.27)
		(stroke
			(width 0)
			(type default)
		)
	)
	(bus_entry
		(at 243.84 91.44)
		(size 1.27 -1.27)
		(stroke
			(width 0)
			(type default)
		)
	)
	(bus_entry
		(at 243.84 102.87)
		(size 1.27 -1.27)
		(stroke
			(width 0)
			(type default)
		)
	)
	(bus_entry
		(at 243.84 127)
		(size 1.27 -1.27)
		(stroke
			(width 0)
			(type default)
		)
	)
	(bus_entry
		(at 149.86 100.33)
		(size -1.27 -1.27)
		(stroke
			(width 0)
			(type default)
		)
	)
	(bus_entry
		(at 149.86 121.92)
		(size -1.27 -1.27)
		(stroke
			(width 0)
			(type default)
		)
	)
	(bus_entry
		(at 243.84 107.95)
		(size 1.27 -1.27)
		(stroke
			(width 0)
			(type default)
		)
	)
	(bus_entry
		(at 149.86 113.03)
		(size -1.27 -1.27)
		(stroke
			(width 0)
			(type default)
		)
	)
	(bus_entry
		(at 149.86 124.46)
		(size -1.27 -1.27)
		(stroke
			(width 0)
			(type default)
		)
	)
	(bus_entry
		(at 243.84 88.9)
		(size 1.27 -1.27)
		(stroke
			(width 0)
			(type default)
		)
	)
	(bus_entry
		(at 149.86 115.57)
		(size -1.27 -1.27)
		(stroke
			(width 0)
			(type default)
		)
	)
	(bus_entry
		(at 149.86 107.95)
		(size -1.27 -1.27)
		(stroke
			(width 0)
			(type default)
		)
	)
	(bus_entry
		(at 149.86 96.52)
		(size -1.27 -1.27)
		(stroke
			(width 0)
			(type default)
		)
	)
	(bus_entry
		(at 243.84 124.46)
		(size 1.27 -1.27)
		(stroke
			(width 0)
			(type default)
		)
	)
	(bus_entry
		(at 243.84 83.82)
		(size 1.27 -1.27)
		(stroke
			(width 0)
			(type default)
		)
	)
	(bus_entry
		(at 149.86 78.74)
		(size -1.27 -1.27)
		(stroke
			(width 0)
			(type default)
		)
	)
	(bus_entry
		(at 149.86 102.87)
		(size -1.27 -1.27)
		(stroke
			(width 0)
			(type default)
		)
	)
	(bus_entry
		(at 149.86 93.98)
		(size -1.27 -1.27)
		(stroke
			(width 0)
			(type default)
		)
	)
	(bus_entry
		(at 243.84 96.52)
		(size 1.27 -1.27)
		(stroke
			(width 0)
			(type default)
		)
	)
	(bus_entry
		(at 243.84 129.54)
		(size 1.27 -1.27)
		(stroke
			(width 0)
			(type default)
		)
	)
	(bus_entry
		(at 243.84 86.36)
		(size 1.27 -1.27)
		(stroke
			(width 0)
			(type default)
		)
	)
	(bus_entry
		(at 149.86 81.28)
		(size -1.27 -1.27)
		(stroke
			(width 0)
			(type default)
		)
	)
	(bus_entry
		(at 243.84 113.03)
		(size 1.27 -1.27)
		(stroke
			(width 0)
			(type default)
		)
	)
	(bus_entry
		(at 149.86 91.44)
		(size -1.27 -1.27)
		(stroke
			(width 0)
			(type default)
		)
	)
	(bus_entry
		(at 243.84 115.57)
		(size 1.27 -1.27)
		(stroke
			(width 0)
			(type default)
		)
	)
	(wire
		(pts
			(xy 149.86 121.92) (xy 172.72 121.92)
		)
		(stroke
			(width 0)
			(type default)
		)
	)
	(wire
		(pts
			(xy 149.86 105.41) (xy 172.72 105.41)
		)
		(stroke
			(width 0)
			(type default)
		)
	)
	(bus
		(pts
			(xy 148.59 116.84) (xy 148.59 120.65)
		)
		(stroke
			(width 0)
			(type default)
		)
	)
	(wire
		(pts
			(xy 243.84 93.98) (xy 220.98 93.98)
		)
		(stroke
			(width 0)
			(type default)
		)
	)
	(wire
		(pts
			(xy 243.84 110.49) (xy 220.98 110.49)
		)
		(stroke
			(width 0)
			(type default)
		)
	)
	(bus
		(pts
			(xy 148.59 92.71) (xy 148.59 95.25)
		)
		(stroke
			(width 0)
			(type default)
		)
	)
	(bus
		(pts
			(xy 245.11 77.47) (xy 245.11 80.01)
		)
		(stroke
			(width 0)
			(type default)
		)
	)
	(wire
		(pts
			(xy 243.84 115.57) (xy 220.98 115.57)
		)
		(stroke
			(width 0)
			(type default)
		)
	)
	(wire
		(pts
			(xy 149.86 100.33) (xy 172.72 100.33)
		)
		(stroke
			(width 0)
			(type default)
		)
	)
	(wire
		(pts
			(xy 243.84 86.36) (xy 220.98 86.36)
		)
		(stroke
			(width 0)
			(type default)
		)
	)
	(bus
		(pts
			(xy 148.59 114.3) (xy 148.59 116.84)
		)
		(stroke
			(width 0)
			(type default)
		)
	)
	(wire
		(pts
			(xy 243.84 96.52) (xy 220.98 96.52)
		)
		(stroke
			(width 0)
			(type default)
		)
	)
	(wire
		(pts
			(xy 243.84 107.95) (xy 220.98 107.95)
		)
		(stroke
			(width 0)
			(type default)
		)
	)
	(wire
		(pts
			(xy 243.84 118.11) (xy 220.98 118.11)
		)
		(stroke
			(width 0)
			(type default)
		)
	)
	(bus
		(pts
			(xy 246.38 73.66) (xy 245.11 74.93)
		)
		(stroke
			(width 0)
			(type default)
		)
	)
	(bus
		(pts
			(xy 148.59 95.25) (xy 148.59 99.06)
		)
		(stroke
			(width 0)
			(type default)
		)
	)
	(bus
		(pts
			(xy 245.11 104.14) (xy 245.11 106.68)
		)
		(stroke
			(width 0)
			(type default)
		)
	)
	(wire
		(pts
			(xy 149.86 88.9) (xy 172.72 88.9)
		)
		(stroke
			(width 0)
			(type default)
		)
	)
	(wire
		(pts
			(xy 243.84 100.33) (xy 220.98 100.33)
		)
		(stroke
			(width 0)
			(type default)
		)
	)
	(bus
		(pts
			(xy 245.11 116.84) (xy 245.11 120.65)
		)
		(stroke
			(width 0)
			(type default)
		)
	)
	(wire
		(pts
			(xy 243.84 124.46) (xy 220.98 124.46)
		)
		(stroke
			(width 0)
			(type default)
		)
	)
	(wire
		(pts
			(xy 149.86 91.44) (xy 172.72 91.44)
		)
		(stroke
			(width 0)
			(type default)
		)
	)
	(wire
		(pts
			(xy 149.86 86.36) (xy 172.72 86.36)
		)
		(stroke
			(width 0)
			(type default)
		)
	)
	(wire
		(pts
			(xy 149.86 107.95) (xy 172.72 107.95)
		)
		(stroke
			(width 0)
			(type default)
		)
	)
	(bus
		(pts
			(xy 148.59 111.76) (xy 148.59 114.3)
		)
		(stroke
			(width 0)
			(type default)
		)
	)
	(bus
		(pts
			(xy 245.11 99.06) (xy 245.11 101.6)
		)
		(stroke
			(width 0)
			(type default)
		)
	)
	(wire
		(pts
			(xy 243.84 81.28) (xy 220.98 81.28)
		)
		(stroke
			(width 0)
			(type default)
		)
	)
	(bus
		(pts
			(xy 148.59 109.22) (xy 148.59 111.76)
		)
		(stroke
			(width 0)
			(type default)
		)
	)
	(wire
		(pts
			(xy 149.86 78.74) (xy 172.72 78.74)
		)
		(stroke
			(width 0)
			(type default)
		)
	)
	(bus
		(pts
			(xy 148.59 120.65) (xy 148.59 123.19)
		)
		(stroke
			(width 0)
			(type default)
		)
	)
	(bus
		(pts
			(xy 148.59 90.17) (xy 148.59 92.71)
		)
		(stroke
			(width 0)
			(type default)
		)
	)
	(wire
		(pts
			(xy 149.86 129.54) (xy 172.72 129.54)
		)
		(stroke
			(width 0)
			(type default)
		)
	)
	(wire
		(pts
			(xy 149.86 93.98) (xy 172.72 93.98)
		)
		(stroke
			(width 0)
			(type default)
		)
	)
	(bus
		(pts
			(xy 148.59 104.14) (xy 148.59 106.68)
		)
		(stroke
			(width 0)
			(type default)
		)
	)
	(bus
		(pts
			(xy 148.59 87.63) (xy 148.59 90.17)
		)
		(stroke
			(width 0)
			(type default)
		)
	)
	(bus
		(pts
			(xy 245.11 85.09) (xy 245.11 87.63)
		)
		(stroke
			(width 0)
			(type default)
		)
	)
	(bus
		(pts
			(xy 148.59 77.47) (xy 148.59 80.01)
		)
		(stroke
			(width 0)
			(type default)
		)
	)
	(bus
		(pts
			(xy 245.11 114.3) (xy 245.11 116.84)
		)
		(stroke
			(width 0)
			(type default)
		)
	)
	(bus
		(pts
			(xy 148.59 101.6) (xy 148.59 104.14)
		)
		(stroke
			(width 0)
			(type default)
		)
	)
	(bus
		(pts
			(xy 148.59 74.93) (xy 148.59 77.47)
		)
		(stroke
			(width 0)
			(type default)
		)
	)
	(bus
		(pts
			(xy 245.11 125.73) (xy 245.11 128.27)
		)
		(stroke
			(width 0)
			(type default)
		)
	)
	(bus
		(pts
			(xy 148.59 99.06) (xy 148.59 101.6)
		)
		(stroke
			(width 0)
			(type default)
		)
	)
	(wire
		(pts
			(xy 243.84 121.92) (xy 220.98 121.92)
		)
		(stroke
			(width 0)
			(type default)
		)
	)
	(bus
		(pts
			(xy 148.59 82.55) (xy 148.59 85.09)
		)
		(stroke
			(width 0)
			(type default)
		)
	)
	(wire
		(pts
			(xy 243.84 102.87) (xy 220.98 102.87)
		)
		(stroke
			(width 0)
			(type default)
		)
	)
	(bus
		(pts
			(xy 128.27 73.66) (xy 147.32 73.66)
		)
		(stroke
			(width 0)
			(type default)
		)
	)
	(bus
		(pts
			(xy 245.11 120.65) (xy 245.11 123.19)
		)
		(stroke
			(width 0)
			(type default)
		)
	)
	(bus
		(pts
			(xy 245.11 87.63) (xy 245.11 90.17)
		)
		(stroke
			(width 0)
			(type default)
		)
	)
	(wire
		(pts
			(xy 243.84 83.82) (xy 220.98 83.82)
		)
		(stroke
			(width 0)
			(type default)
		)
	)
	(bus
		(pts
			(xy 245.11 82.55) (xy 245.11 85.09)
		)
		(stroke
			(width 0)
			(type default)
		)
	)
	(bus
		(pts
			(xy 245.11 111.76) (xy 245.11 114.3)
		)
		(stroke
			(width 0)
			(type default)
		)
	)
	(wire
		(pts
			(xy 243.84 105.41) (xy 220.98 105.41)
		)
		(stroke
			(width 0)
			(type default)
		)
	)
	(wire
		(pts
			(xy 243.84 88.9) (xy 220.98 88.9)
		)
		(stroke
			(width 0)
			(type default)
		)
	)
	(wire
		(pts
			(xy 149.86 110.49) (xy 172.72 110.49)
		)
		(stroke
			(width 0)
			(type default)
		)
	)
	(wire
		(pts
			(xy 149.86 83.82) (xy 172.72 83.82)
		)
		(stroke
			(width 0)
			(type default)
		)
	)
	(bus
		(pts
			(xy 245.11 80.01) (xy 245.11 82.55)
		)
		(stroke
			(width 0)
			(type default)
		)
	)
	(wire
		(pts
			(xy 149.86 81.28) (xy 172.72 81.28)
		)
		(stroke
			(width 0)
			(type default)
		)
	)
	(wire
		(pts
			(xy 149.86 124.46) (xy 172.72 124.46)
		)
		(stroke
			(width 0)
			(type default)
		)
	)
	(wire
		(pts
			(xy 243.84 129.54) (xy 220.98 129.54)
		)
		(stroke
			(width 0)
			(type default)
		)
	)
	(wire
		(pts
			(xy 243.84 127) (xy 220.98 127)
		)
		(stroke
			(width 0)
			(type default)
		)
	)
	(wire
		(pts
			(xy 149.86 118.11) (xy 172.72 118.11)
		)
		(stroke
			(width 0)
			(type default)
		)
	)
	(bus
		(pts
			(xy 245.11 90.17) (xy 245.11 92.71)
		)
		(stroke
			(width 0)
			(type default)
		)
	)
	(bus
		(pts
			(xy 147.32 73.66) (xy 148.59 74.93)
		)
		(stroke
			(width 0)
			(type default)
		)
	)
	(bus
		(pts
			(xy 148.59 80.01) (xy 148.59 82.55)
		)
		(stroke
			(width 0)
			(type default)
		)
	)
	(wire
		(pts
			(xy 149.86 102.87) (xy 172.72 102.87)
		)
		(stroke
			(width 0)
			(type default)
		)
	)
	(wire
		(pts
			(xy 149.86 127) (xy 172.72 127)
		)
		(stroke
			(width 0)
			(type default)
		)
	)
	(wire
		(pts
			(xy 149.86 115.57) (xy 172.72 115.57)
		)
		(stroke
			(width 0)
			(type default)
		)
	)
	(bus
		(pts
			(xy 245.11 74.93) (xy 245.11 77.47)
		)
		(stroke
			(width 0)
			(type default)
		)
	)
	(bus
		(pts
			(xy 245.11 101.6) (xy 245.11 104.14)
		)
		(stroke
			(width 0)
			(type default)
		)
	)
	(bus
		(pts
			(xy 245.11 106.68) (xy 245.11 109.22)
		)
		(stroke
			(width 0)
			(type default)
		)
	)
	(bus
		(pts
			(xy 265.43 73.66) (xy 246.38 73.66)
		)
		(stroke
			(width 0)
			(type default)
		)
	)
	(wire
		(pts
			(xy 243.84 91.44) (xy 220.98 91.44)
		)
		(stroke
			(width 0)
			(type default)
		)
	)
	(wire
		(pts
			(xy 243.84 78.74) (xy 220.98 78.74)
		)
		(stroke
			(width 0)
			(type default)
		)
	)
	(bus
		(pts
			(xy 148.59 123.19) (xy 148.59 125.73)
		)
		(stroke
			(width 0)
			(type default)
		)
	)
	(bus
		(pts
			(xy 245.11 109.22) (xy 245.11 111.76)
		)
		(stroke
			(width 0)
			(type default)
		)
	)
	(bus
		(pts
			(xy 148.59 125.73) (xy 148.59 128.27)
		)
		(stroke
			(width 0)
			(type default)
		)
	)
	(bus
		(pts
			(xy 148.59 85.09) (xy 148.59 87.63)
		)
		(stroke
			(width 0)
			(type default)
		)
	)
	(wire
		(pts
			(xy 149.86 96.52) (xy 172.72 96.52)
		)
		(stroke
			(width 0)
			(type default)
		)
	)
	(bus
		(pts
			(xy 245.11 92.71) (xy 245.11 95.25)
		)
		(stroke
			(width 0)
			(type default)
		)
	)
	(bus
		(pts
			(xy 245.11 123.19) (xy 245.11 125.73)
		)
		(stroke
			(width 0)
			(type default)
		)
	)
	(wire
		(pts
			(xy 243.84 113.03) (xy 220.98 113.03)
		)
		(stroke
			(width 0)
			(type default)
		)
	)
	(bus
		(pts
			(xy 148.59 106.68) (xy 148.59 109.22)
		)
		(stroke
			(width 0)
			(type default)
		)
	)
	(wire
		(pts
			(xy 149.86 113.03) (xy 172.72 113.03)
		)
		(stroke
			(width 0)
			(type default)
		)
	)
	(bus
		(pts
			(xy 245.11 95.25) (xy 245.11 99.06)
		)
		(stroke
			(width 0)
			(type default)
		)
	)
	(label "GTX116.RX3_P"
		(at 241.3 105.41 180)
		(effects
			(font
				(size 1.27 1.27)
			)
			(justify right bottom)
		)
	)
	(label "GTX116.RX1_N"
		(at 241.3 118.11 180)
		(effects
			(font
				(size 1.27 1.27)
			)
			(justify right bottom)
		)
	)
	(label "GTX115.RX3_P"
		(at 152.4 115.57 0)
		(effects
			(font
				(size 1.27 1.27)
			)
			(justify left bottom)
		)
	)
	(label "GTX115.TX1_N"
		(at 152.4 86.36 0)
		(effects
			(font
				(size 1.27 1.27)
			)
			(justify left bottom)
		)
	)
	(label "GTX116.TX3_P"
		(at 241.3 93.98 180)
		(effects
			(font
				(size 1.27 1.27)
			)
			(justify right bottom)
		)
	)
	(label "GTX115.REFCLK1_N"
		(at 152.4 129.54 0)
		(effects
			(font
				(size 1.27 1.27)
			)
			(justify left bottom)
		)
	)
	(label "GTX116.RX2_N"
		(at 241.3 113.03 180)
		(effects
			(font
				(size 1.27 1.27)
			)
			(justify right bottom)
		)
	)
	(label "GTX115.TX1_P"
		(at 152.4 83.82 0)
		(effects
			(font
				(size 1.27 1.27)
			)
			(justify left bottom)
		)
	)
	(label "GTX116.TX0_P"
		(at 241.3 78.74 180)
		(effects
			(font
				(size 1.27 1.27)
			)
			(justify right bottom)
		)
	)
	(label "GTX115.RX3_N"
		(at 152.4 118.11 0)
		(effects
			(font
				(size 1.27 1.27)
			)
			(justify left bottom)
		)
	)
	(label "GTX116.REFCLK0_N"
		(at 241.3 124.46 180)
		(effects
			(font
				(size 1.27 1.27)
			)
			(justify right bottom)
		)
	)
	(label "GTX116.TX2_N"
		(at 241.3 91.44 180)
		(effects
			(font
				(size 1.27 1.27)
			)
			(justify right bottom)
		)
	)
	(label "GTX115.RX1_P"
		(at 152.4 105.41 0)
		(effects
			(font
				(size 1.27 1.27)
			)
			(justify left bottom)
		)
	)
	(label "GTX115.REFCLK0_P"
		(at 152.4 121.92 0)
		(effects
			(font
				(size 1.27 1.27)
			)
			(justify left bottom)
		)
	)
	(label "GTX116.REFCLK1_P"
		(at 241.3 127 180)
		(effects
			(font
				(size 1.27 1.27)
			)
			(justify right bottom)
		)
	)
	(label "GTX116.RX0_P"
		(at 241.3 100.33 180)
		(effects
			(font
				(size 1.27 1.27)
			)
			(justify right bottom)
		)
	)
	(label "GTX116.REFCLK0_P"
		(at 241.3 121.92 180)
		(effects
			(font
				(size 1.27 1.27)
			)
			(justify right bottom)
		)
	)
	(label "GTX115.TX3_P"
		(at 152.4 88.9 0)
		(effects
			(font
				(size 1.27 1.27)
			)
			(justify left bottom)
		)
	)
	(label "GTX116.RX1_P"
		(at 241.3 115.57 180)
		(effects
			(font
				(size 1.27 1.27)
			)
			(justify right bottom)
		)
	)
	(label "GTX115.TX0_P"
		(at 152.4 93.98 0)
		(effects
			(font
				(size 1.27 1.27)
			)
			(justify left bottom)
		)
	)
	(label "GTX115.RX2_P"
		(at 152.4 110.49 0)
		(effects
			(font
				(size 1.27 1.27)
			)
			(justify left bottom)
		)
	)
	(label "GTX116.RX2_P"
		(at 241.3 110.49 180)
		(effects
			(font
				(size 1.27 1.27)
			)
			(justify right bottom)
		)
	)
	(label "GTX116.REFCLK1_N"
		(at 241.3 129.54 180)
		(effects
			(font
				(size 1.27 1.27)
			)
			(justify right bottom)
		)
	)
	(label "GTX115.TX0_N"
		(at 152.4 96.52 0)
		(effects
			(font
				(size 1.27 1.27)
			)
			(justify left bottom)
		)
	)
	(label "GTX115.REFCLK1_P"
		(at 152.4 127 0)
		(effects
			(font
				(size 1.27 1.27)
			)
			(justify left bottom)
		)
	)
	(label "GTX115.RX0_P"
		(at 152.4 100.33 0)
		(effects
			(font
				(size 1.27 1.27)
			)
			(justify left bottom)
		)
	)
	(label "GTX116.TX1_P"
		(at 241.3 83.82 180)
		(effects
			(font
				(size 1.27 1.27)
			)
			(justify right bottom)
		)
	)
	(label "GTX115.TX2_P"
		(at 152.4 78.74 0)
		(effects
			(font
				(size 1.27 1.27)
			)
			(justify left bottom)
		)
	)
	(label "GTX115.TX3_N"
		(at 152.4 91.44 0)
		(effects
			(font
				(size 1.27 1.27)
			)
			(justify left bottom)
		)
	)
	(label "GTX115.TX2_N"
		(at 152.4 81.28 0)
		(effects
			(font
				(size 1.27 1.27)
			)
			(justify left bottom)
		)
	)
	(label "GTX116.TX0_N"
		(at 241.3 81.28 180)
		(effects
			(font
				(size 1.27 1.27)
			)
			(justify right bottom)
		)
	)
	(label "GTX116.RX3_N"
		(at 241.3 107.95 180)
		(effects
			(font
				(size 1.27 1.27)
			)
			(justify right bottom)
		)
	)
	(label "GTX116.RX0_N"
		(at 241.3 102.87 180)
		(effects
			(font
				(size 1.27 1.27)
			)
			(justify right bottom)
		)
	)
	(label "GTX116.TX1_N"
		(at 241.3 86.36 180)
		(effects
			(font
				(size 1.27 1.27)
			)
			(justify right bottom)
		)
	)
	(label "GTX115.RX1_N"
		(at 152.4 107.95 0)
		(effects
			(font
				(size 1.27 1.27)
			)
			(justify left bottom)
		)
	)
	(label "GTX116.TX3_N"
		(at 241.3 96.52 180)
		(effects
			(font
				(size 1.27 1.27)
			)
			(justify right bottom)
		)
	)
	(label "GTX115.REFCLK0_N"
		(at 152.4 124.46 0)
		(effects
			(font
				(size 1.27 1.27)
			)
			(justify left bottom)
		)
	)
	(label "GTX116.TX2_P"
		(at 241.3 88.9 180)
		(effects
			(font
				(size 1.27 1.27)
			)
			(justify right bottom)
		)
	)
	(label "GTX115.RX0_N"
		(at 152.4 102.87 0)
		(effects
			(font
				(size 1.27 1.27)
			)
			(justify left bottom)
		)
	)
	(label "GTX115.RX2_N"
		(at 152.4 113.03 0)
		(effects
			(font
				(size 1.27 1.27)
			)
			(justify left bottom)
		)
	)
	(hierarchical_label "GTX116{MGTX}"
		(shape input)
		(at 265.43 73.66 0)
		(effects
			(font
				(size 1.27 1.27)
			)
			(justify left)
		)
	)
	(hierarchical_label "GTX115{MGTX}"
		(shape input)
		(at 128.27 73.66 180)
		(effects
			(font
				(size 1.27 1.27)
			)
			(justify right)
		)
	)
	(symbol
		(lib_id "antmicroFPGAChips:XC7K410T-2FFG900I")
		(at 172.72 78.74 0)
		(unit 6)
		(exclude_from_sim no)
		(in_bom yes)
		(on_board yes)
		(dnp no)
		(fields_autoplaced yes)
		(property "Reference" "U1"
			(at 200.66 66.04 0)
			(effects
				(font
					(size 1.27 1.27)
					(thickness 0.15)
				)
			)
		)
		(property "Value" "XC7K410T-2FFG900I"
			(at 200.66 68.58 0)
			(effects
				(font
					(size 1.27 1.27)
					(thickness 0.15)
				)
			)
		)
		(property "Footprint" "antmicro-footprints:BGA-900_31x31mm_Layout30x30_P1x1mm_FFG900"
			(at 172.72 52.07 0)
			(effects
				(font
					(size 1.27 1.27)
					(thickness 0.15)
				)
				(justify left bottom)
				(hide yes)
			)
		)
		(property "Datasheet" "https://eu.mouser.com/datasheet/2/903/ds180_7Series_Overview-1591537.pdf"
			(at 172.72 54.61 0)
			(effects
				(font
					(size 1.27 1.27)
					(thickness 0.15)
				)
				(justify left bottom)
				(hide yes)
			)
		)
		(property "Description" ""
			(at 172.72 78.74 0)
			(effects
				(font
					(size 1.27 1.27)
				)
			)
		)
		(property "Manufacturer" "AMD-Xilinx"
			(at 172.72 57.15 0)
			(effects
				(font
					(size 1.27 1.27)
					(thickness 0.15)
				)
				(justify left bottom)
				(hide yes)
			)
		)
		(property "MPN" "XC7K410T-2FFG900I"
			(at 172.72 59.69 0)
			(effects
				(font
					(size 1.27 1.27)
					(thickness 0.15)
				)
				(justify left bottom)
				(hide yes)
			)
		)
		(property "Author" "Antmicro"
			(at 172.72 62.23 0)
			(effects
				(font
					(size 1.27 1.27)
					(thickness 0.15)
				)
				(justify left bottom)
				(hide yes)
			)
		)
		(property "License" "Apache-2.0"
			(at 172.72 64.77 0)
			(effects
				(font
					(size 1.27 1.27)
					(thickness 0.15)
				)
				(justify left bottom)
				(hide yes)
			)
		)
		(pin "A3"
		)
		(pin "A4"
		)
		(pin "A7"
		)
		(pin "A8"
		)
		(pin "AA3"
		)
		(pin "AA4"
		)
		(pin "B1"
		)
		(pin "B2"
		)
		(pin "B5"
		)
		(pin "B6"
		)
		(pin "C3"
		)
		(pin "C4"
		)
		(pin "C7"
		)
		(pin "C8"
		)
		(pin "D1"
		)
		(pin "D2"
		)
		(pin "D5"
		)
		(pin "D6"
		)
		(pin "E3"
		)
		(pin "E4"
		)
		(pin "E7"
		)
		(pin "E8"
		)
		(pin "F1"
		)
		(pin "F2"
		)
		(pin "F5"
		)
		(pin "F6"
		)
		(pin "G3"
		)
		(pin "G4"
		)
		(pin "G7"
		)
		(pin "G8"
		)
		(pin "H1"
		)
		(pin "H2"
		)
		(pin "H5"
		)
		(pin "H6"
		)
		(pin "J3"
		)
		(pin "J4"
		)
		(pin "J7"
		)
		(pin "J8"
		)
		(pin "K1"
		)
		(pin "K2"
		)
		(pin "K5"
		)
		(pin "K6"
		)
		(pin "L3"
		)
		(pin "L4"
		)
		(pin "L7"
		)
		(pin "L8"
		)
		(pin "M1"
		)
		(pin "M2"
		)
		(pin "M5"
		)
		(pin "M6"
		)
		(pin "N3"
		)
		(pin "N4"
		)
		(pin "N7"
		)
		(pin "N8"
		)
		(pin "P1"
		)
		(pin "P2"
		)
		(pin "P5"
		)
		(pin "P6"
		)
		(pin "R3"
		)
		(pin "R4"
		)
		(pin "R7"
		)
		(pin "R8"
		)
		(pin "T1"
		)
		(pin "T2"
		)
		(pin "T5"
		)
		(pin "T6"
		)
		(pin "U3"
		)
		(pin "U4"
		)
		(pin "U7"
		)
		(pin "U8"
		)
		(pin "V1"
		)
		(pin "V2"
		)
		(pin "V5"
		)
		(pin "V6"
		)
		(pin "W3"
		)
		(pin "W4"
		)
		(pin "Y1"
		)
		(pin "Y2"
		)
		(pin "Y5"
		)
		(pin "Y6"
		)
		(pin "E29"
		)
		(pin "AA22"
		)
		(pin "AA23"
		)
		(pin "AB20"
		)
		(pin "AB22"
		)
		(pin "AB23"
		)
		(pin "AB24"
		)
		(pin "AC20"
		)
		(pin "AC21"
		)
		(pin "AC22"
		)
		(pin "AC24"
		)
		(pin "AC25"
		)
		(pin "AD21"
		)
		(pin "AD22"
		)
		(pin "AD23"
		)
		(pin "AD24"
		)
		(pin "AE20"
		)
		(pin "AE21"
		)
		(pin "AE23"
		)
		(pin "AE24"
		)
		(pin "AE25"
		)
		(pin "AF20"
		)
		(pin "AF21"
		)
		(pin "AF22"
		)
		(pin "AF23"
		)
		(pin "AF25"
		)
		(pin "AG20"
		)
		(pin "AG22"
		)
		(pin "AG23"
		)
		(pin "AG24"
		)
		(pin "AG25"
		)
		(pin "AH20"
		)
		(pin "AH21"
		)
		(pin "AH22"
		)
		(pin "AH24"
		)
		(pin "AH25"
		)
		(pin "AJ21"
		)
		(pin "AJ22"
		)
		(pin "AJ23"
		)
		(pin "AJ24"
		)
		(pin "AK20"
		)
		(pin "AK21"
		)
		(pin "AK23"
		)
		(pin "AK24"
		)
		(pin "AK25"
		)
		(pin "Y20"
		)
		(pin "Y21"
		)
		(pin "Y23"
		)
		(pin "Y24"
		)
		(pin "P24"
		)
		(pin "P26"
		)
		(pin "P27"
		)
		(pin "P28"
		)
		(pin "P29"
		)
		(pin "R19"
		)
		(pin "R20"
		)
		(pin "R21"
		)
		(pin "R23"
		)
		(pin "R24"
		)
		(pin "R25"
		)
		(pin "R26"
		)
		(pin "R28"
		)
		(pin "R29"
		)
		(pin "R30"
		)
		(pin "T20"
		)
		(pin "T21"
		)
		(pin "T22"
		)
		(pin "T23"
		)
		(pin "T25"
		)
		(pin "T26"
		)
		(pin "T27"
		)
		(pin "T28"
		)
		(pin "T30"
		)
		(pin "U19"
		)
		(pin "U20"
		)
		(pin "U22"
		)
		(pin "U23"
		)
		(pin "U24"
		)
		(pin "U25"
		)
		(pin "U27"
		)
		(pin "U28"
		)
		(pin "U29"
		)
		(pin "U30"
		)
		(pin "V19"
		)
		(pin "V20"
		)
		(pin "V21"
		)
		(pin "V22"
		)
		(pin "V24"
		)
		(pin "V25"
		)
		(pin "V26"
		)
		(pin "V27"
		)
		(pin "V29"
		)
		(pin "V30"
		)
		(pin "W19"
		)
		(pin "W21"
		)
		(pin "W22"
		)
		(pin "W23"
		)
		(pin "W24"
		)
		(pin "W26"
		)
		(pin "A23"
		)
		(pin "A25"
		)
		(pin "A26"
		)
		(pin "A27"
		)
		(pin "A28"
		)
		(pin "A30"
		)
		(pin "B23"
		)
		(pin "B24"
		)
		(pin "B25"
		)
		(pin "B27"
		)
		(pin "B28"
		)
		(pin "B29"
		)
		(pin "B30"
		)
		(pin "C24"
		)
		(pin "C25"
		)
		(pin "C26"
		)
		(pin "C27"
		)
		(pin "C29"
		)
		(pin "C30"
		)
		(pin "D23"
		)
		(pin "D24"
		)
		(pin "D26"
		)
		(pin "D27"
		)
		(pin "D28"
		)
		(pin "D29"
		)
		(pin "E23"
		)
		(pin "E24"
		)
		(pin "E25"
		)
		(pin "E26"
		)
		(pin "F23"
		)
		(pin "F25"
		)
		(pin "F26"
		)
		(pin "F27"
		)
		(pin "F28"
		)
		(pin "F30"
		)
		(pin "G23"
		)
		(pin "G24"
		)
		(pin "G25"
		)
		(pin "G27"
		)
		(pin "G28"
		)
		(pin "G29"
		)
		(pin "G30"
		)
		(pin "H24"
		)
		(pin "H25"
		)
		(pin "H26"
		)
		(pin "H27"
		)
		(pin "H30"
		)
		(pin "A11"
		)
		(pin "A12"
		)
		(pin "A13"
		)
		(pin "A15"
		)
		(pin "B12"
		)
		(pin "B13"
		)
		(pin "B14"
		)
		(pin "B15"
		)
		(pin "C11"
		)
		(pin "C12"
		)
		(pin "C14"
		)
		(pin "C15"
		)
		(pin "D11"
		)
		(pin "D12"
		)
		(pin "D13"
		)
		(pin "D14"
		)
		(pin "E11"
		)
		(pin "E13"
		)
		(pin "E14"
		)
		(pin "E15"
		)
		(pin "E16"
		)
		(pin "F11"
		)
		(pin "F12"
		)
		(pin "F13"
		)
		(pin "F15"
		)
		(pin "F16"
		)
		(pin "G12"
		)
		(pin "G13"
		)
		(pin "G14"
		)
		(pin "G15"
		)
		(pin "H11"
		)
		(pin "H12"
		)
		(pin "H14"
		)
		(pin "H15"
		)
		(pin "H16"
		)
		(pin "J11"
		)
		(pin "J12"
		)
		(pin "J13"
		)
		(pin "J14"
		)
		(pin "J16"
		)
		(pin "K11"
		)
		(pin "K13"
		)
		(pin "K14"
		)
		(pin "K15"
		)
		(pin "K16"
		)
		(pin "L11"
		)
		(pin "L12"
		)
		(pin "L13"
		)
		(pin "L15"
		)
		(pin "L16"
		)
		(pin "AA10"
		)
		(pin "AA11"
		)
		(pin "AA12"
		)
		(pin "AA13"
		)
		(pin "AA8"
		)
		(pin "AB10"
		)
		(pin "AB12"
		)
		(pin "AB13"
		)
		(pin "AB8"
		)
		(pin "AB9"
		)
		(pin "AC10"
		)
		(pin "AC11"
		)
		(pin "AC12"
		)
		(pin "AC9"
		)
		(pin "AD11"
		)
		(pin "AD12"
		)
		(pin "AD13"
		)
		(pin "AD8"
		)
		(pin "AD9"
		)
		(pin "AE10"
		)
		(pin "AE11"
		)
		(pin "AE13"
		)
		(pin "AE8"
		)
		(pin "AE9"
		)
		(pin "AF10"
		)
		(pin "AF11"
		)
		(pin "AF12"
		)
		(pin "AF13"
		)
		(pin "AG10"
		)
		(pin "AG12"
		)
		(pin "AG13"
		)
		(pin "AG9"
		)
		(pin "AH10"
		)
		(pin "AH11"
		)
		(pin "AH12"
		)
		(pin "AH14"
		)
		(pin "AH9"
		)
		(pin "AJ11"
		)
		(pin "AJ12"
		)
		(pin "AJ13"
		)
		(pin "AJ14"
		)
		(pin "AJ9"
		)
		(pin "AK10"
		)
		(pin "AK11"
		)
		(pin "AK13"
		)
		(pin "AK14"
		)
		(pin "AK9"
		)
		(pin "Y10"
		)
		(pin "Y11"
		)
		(pin "Y13"
		)
		(pin "G16"
		)
		(pin "G2"
		)
		(pin "G26"
		)
		(pin "G6"
		)
		(pin "G9"
		)
		(pin "H13"
		)
		(pin "H23"
		)
		(pin "H4"
		)
		(pin "H8"
		)
		(pin "H9"
		)
		(pin "J1"
		)
		(pin "J10"
		)
		(pin "B3"
		)
		(pin "B7"
		)
		(pin "C5"
		)
		(pin "D3"
		)
		(pin "D7"
		)
		(pin "E5"
		)
		(pin "F3"
		)
		(pin "F7"
		)
		(pin "G5"
		)
		(pin "H3"
		)
		(pin "H7"
		)
		(pin "J5"
		)
		(pin "K3"
		)
		(pin "K7"
		)
		(pin "L5"
		)
		(pin "M3"
		)
		(pin "M7"
		)
		(pin "N5"
		)
		(pin "P3"
		)
		(pin "P7"
		)
		(pin "R5"
		)
		(pin "T3"
		)
		(pin "T7"
		)
		(pin "U5"
		)
		(pin "V3"
		)
		(pin "V7"
		)
		(pin "W5"
		)
		(pin "W7"
		)
		(pin "W8"
		)
		(pin "A10"
		)
		(pin "AB1"
		)
		(pin "AB2"
		)
		(pin "AB5"
		)
		(pin "B10"
		)
		(pin "E10"
		)
		(pin "F10"
		)
		(pin "G10"
		)
		(pin "H10"
		)
		(pin "K10"
		)
		(pin "L10"
		)
		(pin "M10"
		)
		(pin "R14"
		)
		(pin "R15"
		)
		(pin "T14"
		)
		(pin "T15"
		)
		(pin "U14"
		)
		(pin "U15"
		)
		(pin "A19"
		)
		(pin "A29"
		)
		(pin "AA19"
		)
		(pin "AA29"
		)
		(pin "AA9"
		)
		(pin "AB16"
		)
		(pin "AB26"
		)
		(pin "AB6"
		)
		(pin "AC13"
		)
		(pin "AC23"
		)
		(pin "AC3"
		)
		(pin "AD10"
		)
		(pin "AD20"
		)
		(pin "AD30"
		)
		(pin "AE17"
		)
		(pin "AE27"
		)
		(pin "AE7"
		)
		(pin "AF14"
		)
		(pin "AF24"
		)
		(pin "AF4"
		)
		(pin "AG1"
		)
		(pin "AG11"
		)
		(pin "AG21"
		)
		(pin "AH18"
		)
		(pin "AH28"
		)
		(pin "AH8"
		)
		(pin "AJ15"
		)
		(pin "AJ25"
		)
		(pin "AJ5"
		)
		(pin "AK12"
		)
		(pin "AK2"
		)
		(pin "AK22"
		)
		(pin "B16"
		)
		(pin "B26"
		)
		(pin "C13"
		)
		(pin "C23"
		)
		(pin "D10"
		)
		(pin "D20"
		)
		(pin "D30"
		)
		(pin "E17"
		)
		(pin "E27"
		)
		(pin "F14"
		)
		(pin "F24"
		)
		(pin "G11"
		)
		(pin "G21"
		)
		(pin "H18"
		)
		(pin "H28"
		)
		(pin "J15"
		)
		(pin "J25"
		)
		(pin "K12"
		)
		(pin "K22"
		)
		(pin "L19"
		)
		(pin "L29"
		)
		(pin "M26"
		)
		(pin "N23"
		)
		(pin "P20"
		)
		(pin "P30"
		)
		(pin "R27"
		)
		(pin "T24"
		)
		(pin "T9"
		)
		(pin "U21"
		)
		(pin "V28"
		)
		(pin "W25"
		)
		(pin "Y12"
		)
		(pin "Y22"
		)
		(pin "A1"
		)
		(pin "A14"
		)
		(pin "A2"
		)
		(pin "A24"
		)
		(pin "A5"
		)
		(pin "A6"
		)
		(pin "A9"
		)
		(pin "AA1"
		)
		(pin "AA14"
		)
		(pin "AA2"
		)
		(pin "AA24"
		)
		(pin "AA5"
		)
		(pin "AA6"
		)
		(pin "AA7"
		)
		(pin "AB11"
		)
		(pin "AB21"
		)
		(pin "AB3"
		)
		(pin "AB4"
		)
		(pin "AC18"
		)
		(pin "AC28"
		)
		(pin "AC8"
		)
		(pin "AD15"
		)
		(pin "AD25"
		)
		(pin "AD5"
		)
		(pin "AE12"
		)
		(pin "AE2"
		)
		(pin "AE22"
		)
		(pin "AF19"
		)
		(pin "AF29"
		)
		(pin "AF9"
		)
		(pin "AG16"
		)
		(pin "AG26"
		)
		(pin "AG6"
		)
		(pin "AH13"
		)
		(pin "AH23"
		)
		(pin "AH3"
		)
		(pin "AJ10"
		)
		(pin "AJ20"
		)
		(pin "AJ30"
		)
		(pin "AK17"
		)
		(pin "AK27"
		)
		(pin "AK7"
		)
		(pin "B11"
		)
		(pin "B21"
		)
		(pin "B4"
		)
		(pin "B8"
		)
		(pin "B9"
		)
		(pin "C1"
		)
		(pin "C10"
		)
		(pin "C18"
		)
		(pin "C2"
		)
		(pin "C28"
		)
		(pin "C6"
		)
		(pin "C9"
		)
		(pin "D15"
		)
		(pin "D25"
		)
		(pin "D4"
		)
		(pin "D8"
		)
		(pin "D9"
		)
		(pin "E1"
		)
		(pin "E12"
		)
		(pin "E2"
		)
		(pin "E22"
		)
		(pin "E6"
		)
		(pin "E9"
		)
		(pin "F19"
		)
		(pin "F29"
		)
		(pin "F4"
		)
		(pin "F8"
		)
		(pin "F9"
		)
		(pin "G1"
		)
		(pin "J2"
		)
		(pin "J20"
		)
		(pin "J30"
		)
		(pin "J6"
		)
		(pin "J9"
		)
		(pin "K17"
		)
		(pin "K27"
		)
		(pin "K4"
		)
		(pin "K8"
		)
		(pin "K9"
		)
		(pin "L1"
		)
		(pin "L14"
		)
		(pin "L2"
		)
		(pin "L24"
		)
		(pin "L6"
		)
		(pin "L9"
		)
		(pin "M11"
		)
		(pin "M12"
		)
		(pin "M13"
		)
		(pin "M14"
		)
		(pin "M15"
		)
		(pin "M16"
		)
		(pin "M17"
		)
		(pin "M18"
		)
		(pin "M21"
		)
		(pin "M4"
		)
		(pin "M8"
		)
		(pin "M9"
		)
		(pin "N1"
		)
		(pin "N10"
		)
		(pin "N11"
		)
		(pin "N12"
		)
		(pin "N13"
		)
		(pin "N14"
		)
		(pin "N15"
		)
		(pin "N16"
		)
		(pin "N17"
		)
		(pin "N18"
		)
		(pin "N2"
		)
		(pin "N28"
		)
		(pin "N6"
		)
		(pin "N9"
		)
		(pin "P10"
		)
		(pin "P11"
		)
		(pin "P12"
		)
		(pin "P13"
		)
		(pin "P14"
		)
		(pin "P15"
		)
		(pin "P16"
		)
		(pin "P17"
		)
		(pin "P18"
		)
		(pin "P25"
		)
		(pin "P4"
		)
		(pin "P8"
		)
		(pin "P9"
		)
		(pin "R1"
		)
		(pin "R10"
		)
		(pin "R11"
		)
		(pin "R12"
		)
		(pin "R13"
		)
		(pin "R16"
		)
		(pin "R17"
		)
		(pin "R18"
		)
		(pin "R2"
		)
		(pin "R22"
		)
		(pin "R6"
		)
		(pin "R9"
		)
		(pin "T10"
		)
		(pin "T11"
		)
		(pin "T12"
		)
		(pin "T13"
		)
		(pin "T16"
		)
		(pin "T17"
		)
		(pin "T18"
		)
		(pin "T19"
		)
		(pin "T29"
		)
		(pin "T4"
		)
		(pin "T8"
		)
		(pin "U1"
		)
		(pin "U10"
		)
		(pin "U11"
		)
		(pin "U12"
		)
		(pin "U13"
		)
		(pin "U16"
		)
		(pin "U17"
		)
		(pin "U18"
		)
		(pin "U2"
		)
		(pin "U26"
		)
		(pin "U6"
		)
		(pin "U9"
		)
		(pin "V10"
		)
		(pin "V11"
		)
		(pin "V12"
		)
		(pin "V13"
		)
		(pin "V14"
		)
		(pin "V15"
		)
		(pin "V16"
		)
		(pin "V17"
		)
		(pin "V18"
		)
		(pin "V23"
		)
		(pin "V4"
		)
		(pin "V8"
		)
		(pin "V9"
		)
		(pin "W1"
		)
		(pin "W10"
		)
		(pin "W11"
		)
		(pin "W12"
		)
		(pin "W13"
		)
		(pin "W14"
		)
		(pin "W15"
		)
		(pin "W16"
		)
		(pin "W17"
		)
		(pin "W18"
		)
		(pin "W2"
		)
		(pin "W20"
		)
		(pin "W30"
		)
		(pin "W6"
		)
		(pin "W9"
		)
		(pin "Y17"
		)
		(pin "Y27"
		)
		(pin "Y3"
		)
		(pin "Y4"
		)
		(pin "Y7"
		)
		(pin "Y8"
		)
		(pin "Y9"
		)
		(pin "AA25"
		)
		(pin "AA26"
		)
		(pin "AA27"
		)
		(pin "AA28"
		)
		(pin "AA30"
		)
		(pin "AB25"
		)
		(pin "AB27"
		)
		(pin "AB28"
		)
		(pin "AB29"
		)
		(pin "AB30"
		)
		(pin "AC26"
		)
		(pin "AC27"
		)
		(pin "AC29"
		)
		(pin "AC30"
		)
		(pin "AD26"
		)
		(pin "AD27"
		)
		(pin "AD28"
		)
		(pin "AD29"
		)
		(pin "AE26"
		)
		(pin "AE28"
		)
		(pin "AE29"
		)
		(pin "AE30"
		)
		(pin "AF26"
		)
		(pin "AF27"
		)
		(pin "AF28"
		)
		(pin "AF30"
		)
		(pin "AG27"
		)
		(pin "AG28"
		)
		(pin "AG29"
		)
		(pin "AG30"
		)
		(pin "AH26"
		)
		(pin "AH27"
		)
		(pin "AH29"
		)
		(pin "AH30"
		)
		(pin "AJ26"
		)
		(pin "AJ27"
		)
		(pin "AJ28"
		)
		(pin "AJ29"
		)
		(pin "AK26"
		)
		(pin "AK28"
		)
		(pin "AK29"
		)
		(pin "AK30"
		)
		(pin "W27"
		)
		(pin "W28"
		)
		(pin "W29"
		)
		(pin "Y25"
		)
		(pin "Y26"
		)
		(pin "Y28"
		)
		(pin "Y29"
		)
		(pin "Y30"
		)
		(pin "H29"
		)
		(pin "J21"
		)
		(pin "J22"
		)
		(pin "J23"
		)
		(pin "J24"
		)
		(pin "J26"
		)
		(pin "J27"
		)
		(pin "J28"
		)
		(pin "J29"
		)
		(pin "K21"
		)
		(pin "K23"
		)
		(pin "K24"
		)
		(pin "K25"
		)
		(pin "K26"
		)
		(pin "K28"
		)
		(pin "K29"
		)
		(pin "K30"
		)
		(pin "L20"
		)
		(pin "L21"
		)
		(pin "L22"
		)
		(pin "L23"
		)
		(pin "L25"
		)
		(pin "L26"
		)
		(pin "L27"
		)
		(pin "L28"
		)
		(pin "L30"
		)
		(pin "M19"
		)
		(pin "M20"
		)
		(pin "M22"
		)
		(pin "M23"
		)
		(pin "M24"
		)
		(pin "M25"
		)
		(pin "M27"
		)
		(pin "M28"
		)
		(pin "M29"
		)
		(pin "M30"
		)
		(pin "N19"
		)
		(pin "N20"
		)
		(pin "N21"
		)
		(pin "N22"
		)
		(pin "N24"
		)
		(pin "N25"
		)
		(pin "N26"
		)
		(pin "N27"
		)
		(pin "N29"
		)
		(pin "N30"
		)
		(pin "P19"
		)
		(pin "P21"
		)
		(pin "P22"
		)
		(pin "P23"
		)
		(pin "A16"
		)
		(pin "A17"
		)
		(pin "A18"
		)
		(pin "A20"
		)
		(pin "A21"
		)
		(pin "A22"
		)
		(pin "B17"
		)
		(pin "B18"
		)
		(pin "B19"
		)
		(pin "B20"
		)
		(pin "B22"
		)
		(pin "C16"
		)
		(pin "C17"
		)
		(pin "C19"
		)
		(pin "C20"
		)
		(pin "C21"
		)
		(pin "C22"
		)
		(pin "D16"
		)
		(pin "D17"
		)
		(pin "D18"
		)
		(pin "D19"
		)
		(pin "D21"
		)
		(pin "D22"
		)
		(pin "E18"
		)
		(pin "E19"
		)
		(pin "E20"
		)
		(pin "E21"
		)
		(pin "F17"
		)
		(pin "F18"
		)
		(pin "F20"
		)
		(pin "F21"
		)
		(pin "F22"
		)
		(pin "G17"
		)
		(pin "G18"
		)
		(pin "G19"
		)
		(pin "G20"
		)
		(pin "G22"
		)
		(pin "H17"
		)
		(pin "H19"
		)
		(pin "H20"
		)
		(pin "H21"
		)
		(pin "H22"
		)
		(pin "J17"
		)
		(pin "J18"
		)
		(pin "J19"
		)
		(pin "K18"
		)
		(pin "K19"
		)
		(pin "K20"
		)
		(pin "L17"
		)
		(pin "L18"
		)
		(pin "AA15"
		)
		(pin "AA16"
		)
		(pin "AA17"
		)
		(pin "AA18"
		)
		(pin "AB14"
		)
		(pin "AB15"
		)
		(pin "AB17"
		)
		(pin "AB18"
		)
		(pin "AB19"
		)
		(pin "AC14"
		)
		(pin "AC15"
		)
		(pin "AC16"
		)
		(pin "AC17"
		)
		(pin "AC19"
		)
		(pin "AD14"
		)
		(pin "AD16"
		)
		(pin "AD17"
		)
		(pin "AD18"
		)
		(pin "AD19"
		)
		(pin "AE14"
		)
		(pin "AE15"
		)
		(pin "AE16"
		)
		(pin "AE18"
		)
		(pin "AE19"
		)
		(pin "AF15"
		)
		(pin "AF16"
		)
		(pin "AF17"
		)
		(pin "AF18"
		)
		(pin "AG14"
		)
		(pin "AG15"
		)
		(pin "AG17"
		)
		(pin "AG18"
		)
		(pin "AG19"
		)
		(pin "AH15"
		)
		(pin "AH16"
		)
		(pin "AH17"
		)
		(pin "AH19"
		)
		(pin "AJ16"
		)
		(pin "AJ17"
		)
		(pin "AJ18"
		)
		(pin "AJ19"
		)
		(pin "AK15"
		)
		(pin "AK16"
		)
		(pin "AK18"
		)
		(pin "AK19"
		)
		(pin "Y14"
		)
		(pin "Y15"
		)
		(pin "Y16"
		)
		(pin "Y18"
		)
		(pin "Y19"
		)
		(pin "AB7"
		)
		(pin "AC1"
		)
		(pin "AC2"
		)
		(pin "AC4"
		)
		(pin "AC5"
		)
		(pin "AC6"
		)
		(pin "AC7"
		)
		(pin "AD1"
		)
		(pin "AD2"
		)
		(pin "AD3"
		)
		(pin "AD4"
		)
		(pin "AD6"
		)
		(pin "AD7"
		)
		(pin "AE1"
		)
		(pin "AE3"
		)
		(pin "AE4"
		)
		(pin "AE5"
		)
		(pin "AE6"
		)
		(pin "AF1"
		)
		(pin "AF2"
		)
		(pin "AF3"
		)
		(pin "AF5"
		)
		(pin "AF6"
		)
		(pin "AF7"
		)
		(pin "AF8"
		)
		(pin "AG2"
		)
		(pin "AG3"
		)
		(pin "AG4"
		)
		(pin "AG5"
		)
		(pin "AG7"
		)
		(pin "AG8"
		)
		(pin "AH1"
		)
		(pin "AH2"
		)
		(pin "AH4"
		)
		(pin "AH5"
		)
		(pin "AH6"
		)
		(pin "AH7"
		)
		(pin "AJ1"
		)
		(pin "AJ2"
		)
		(pin "AJ3"
		)
		(pin "AJ4"
		)
		(pin "AJ6"
		)
		(pin "AJ7"
		)
		(pin "AJ8"
		)
		(pin "AK1"
		)
		(pin "AK3"
		)
		(pin "AK4"
		)
		(pin "AK5"
		)
		(pin "AK6"
		)
		(pin "AK8"
		)
		(pin "AA20"
		)
		(pin "AA21"
		)
		(pin "E30"
		)
		(pin "E28"
		)
		(instances
			(project "k410t-devboard"
				(path ""
					(reference "U1")
					(unit 6)
				)
			)
		)
	)
	(symbol
		(lib_name "XC7K410T-2FFG900I_1")
		(lib_id "antmicroFPGAChips:XC7K410T-2FFG900I")
		(at 172.72 148.59 0)
		(unit 7)
		(exclude_from_sim no)
		(in_bom yes)
		(on_board yes)
		(dnp no)
		(property "Reference" "U1"
			(at 196.85 138.43 0)
			(effects
				(font
					(size 1.27 1.27)
					(thickness 0.15)
				)
			)
		)
		(property "Value" "XC7K410T-2FFG900I"
			(at 255.27 156.21 0)
			(effects
				(font
					(size 1.27 1.27)
					(thickness 0.15)
				)
				(justify left bottom)
				(hide yes)
			)
		)
		(property "Footprint" "antmicro-footprints:BGA-900_31x31mm_Layout30x30_P1x1mm_FFG900"
			(at 255.27 158.75 0)
			(effects
				(font
					(size 1.27 1.27)
					(thickness 0.15)
				)
				(justify left bottom)
				(hide yes)
			)
		)
		(property "Datasheet" "https://eu.mouser.com/datasheet/2/903/ds180_7Series_Overview-1591537.pdf"
			(at 255.27 161.29 0)
			(effects
				(font
					(size 1.27 1.27)
					(thickness 0.15)
				)
				(justify left bottom)
				(hide yes)
			)
		)
		(property "Description" ""
			(at 172.72 148.59 0)
			(effects
				(font
					(size 1.27 1.27)
				)
			)
		)
		(property "MPN" "XC7K410T-2FFG900I"
			(at 196.85 140.97 0)
			(effects
				(font
					(size 1.27 1.27)
					(thickness 0.15)
				)
			)
		)
		(property "Manufacturer" "AMD-Xilinx"
			(at 255.27 163.83 0)
			(effects
				(font
					(size 1.27 1.27)
					(thickness 0.15)
				)
				(justify left bottom)
				(hide yes)
			)
		)
		(property "Author" "Antmicro"
			(at 255.27 166.37 0)
			(effects
				(font
					(size 1.27 1.27)
					(thickness 0.15)
				)
				(justify left bottom)
				(hide yes)
			)
		)
		(property "License" "Apache-2.0"
			(at 255.27 168.91 0)
			(effects
				(font
					(size 1.27 1.27)
					(thickness 0.15)
				)
				(justify left bottom)
				(hide yes)
			)
		)
		(pin "W10"
		)
		(pin "W11"
		)
		(pin "W12"
		)
		(pin "AB25"
		)
		(pin "AB19"
		)
		(pin "AC14"
		)
		(pin "L8"
		)
		(pin "M1"
		)
		(pin "T11"
		)
		(pin "T12"
		)
		(pin "T13"
		)
		(pin "V12"
		)
		(pin "V13"
		)
		(pin "V14"
		)
		(pin "AF22"
		)
		(pin "W28"
		)
		(pin "Y2"
		)
		(pin "Y5"
		)
		(pin "Y6"
		)
		(pin "K20"
		)
		(pin "L17"
		)
		(pin "N10"
		)
		(pin "N11"
		)
		(pin "N12"
		)
		(pin "P22"
		)
		(pin "L18"
		)
		(pin "L19"
		)
		(pin "AJ25"
		)
		(pin "P30"
		)
		(pin "AE23"
		)
		(pin "B29"
		)
		(pin "N20"
		)
		(pin "AC28"
		)
		(pin "AC8"
		)
		(pin "AD15"
		)
		(pin "AJ21"
		)
		(pin "AJ28"
		)
		(pin "H10"
		)
		(pin "K10"
		)
		(pin "L10"
		)
		(pin "K25"
		)
		(pin "R19"
		)
		(pin "R29"
		)
		(pin "AB3"
		)
		(pin "AB4"
		)
		(pin "AC18"
		)
		(pin "H15"
		)
		(pin "H16"
		)
		(pin "AG26"
		)
		(pin "AG6"
		)
		(pin "AH13"
		)
		(pin "D26"
		)
		(pin "D27"
		)
		(pin "AD27"
		)
		(pin "AE17"
		)
		(pin "AE18"
		)
		(pin "R6"
		)
		(pin "R9"
		)
		(pin "T10"
		)
		(pin "N2"
		)
		(pin "N28"
		)
		(pin "N6"
		)
		(pin "H22"
		)
		(pin "H24"
		)
		(pin "E5"
		)
		(pin "F3"
		)
		(pin "F7"
		)
		(pin "D30"
		)
		(pin "E17"
		)
		(pin "AD28"
		)
		(pin "AJ23"
		)
		(pin "A11"
		)
		(pin "A12"
		)
		(pin "AF17"
		)
		(pin "AF18"
		)
		(pin "M22"
		)
		(pin "V2"
		)
		(pin "V5"
		)
		(pin "V6"
		)
		(pin "AC13"
		)
		(pin "AC2"
		)
		(pin "AD26"
		)
		(pin "AC26"
		)
		(pin "D10"
		)
		(pin "D11"
		)
		(pin "AH20"
		)
		(pin "AK9"
		)
		(pin "Y10"
		)
		(pin "P28"
		)
		(pin "P21"
		)
		(pin "K1"
		)
		(pin "K2"
		)
		(pin "K5"
		)
		(pin "AC20"
		)
		(pin "B25"
		)
		(pin "B26"
		)
		(pin "A16"
		)
		(pin "A17"
		)
		(pin "M26"
		)
		(pin "N22"
		)
		(pin "E25"
		)
		(pin "AK27"
		)
		(pin "AK7"
		)
		(pin "B11"
		)
		(pin "N3"
		)
		(pin "N4"
		)
		(pin "N7"
		)
		(pin "AG27"
		)
		(pin "J30"
		)
		(pin "J6"
		)
		(pin "J9"
		)
		(pin "W5"
		)
		(pin "W7"
		)
		(pin "W8"
		)
		(pin "D28"
		)
		(pin "D29"
		)
		(pin "E13"
		)
		(pin "E14"
		)
		(pin "AH26"
		)
		(pin "R27"
		)
		(pin "A8"
		)
		(pin "B1"
		)
		(pin "B2"
		)
		(pin "P29"
		)
		(pin "AF23"
		)
		(pin "B23"
		)
		(pin "B24"
		)
		(pin "AH29"
		)
		(pin "U25"
		)
		(pin "A14"
		)
		(pin "A2"
		)
		(pin "A24"
		)
		(pin "AK2"
		)
		(pin "AK3"
		)
		(pin "AK4"
		)
		(pin "AC17"
		)
		(pin "AC19"
		)
		(pin "AF6"
		)
		(pin "AF7"
		)
		(pin "J28"
		)
		(pin "U28"
		)
		(pin "L29"
		)
		(pin "L28"
		)
		(pin "E10"
		)
		(pin "F10"
		)
		(pin "G10"
		)
		(pin "T25"
		)
		(pin "AH18"
		)
		(pin "AH19"
		)
		(pin "AF29"
		)
		(pin "AF9"
		)
		(pin "AG16"
		)
		(pin "T8"
		)
		(pin "U1"
		)
		(pin "U10"
		)
		(pin "AF21"
		)
		(pin "J18"
		)
		(pin "J19"
		)
		(pin "A22"
		)
		(pin "A23"
		)
		(pin "AB17"
		)
		(pin "AB18"
		)
		(pin "AA28"
		)
		(pin "M23"
		)
		(pin "AA22"
		)
		(pin "H27"
		)
		(pin "H28"
		)
		(pin "AK12"
		)
		(pin "AK13"
		)
		(pin "AK14"
		)
		(pin "AH14"
		)
		(pin "AH2"
		)
		(pin "J10"
		)
		(pin "J2"
		)
		(pin "J20"
		)
		(pin "AH23"
		)
		(pin "AH3"
		)
		(pin "AJ10"
		)
		(pin "W27"
		)
		(pin "M20"
		)
		(pin "AE30"
		)
		(pin "K8"
		)
		(pin "K9"
		)
		(pin "L1"
		)
		(pin "AE19"
		)
		(pin "AF14"
		)
		(pin "AH28"
		)
		(pin "N19"
		)
		(pin "AK22"
		)
		(pin "AF26"
		)
		(pin "E28"
		)
		(pin "E29"
		)
		(pin "K21"
		)
		(pin "AC30"
		)
		(pin "AG2"
		)
		(pin "AG3"
		)
		(pin "K29"
		)
		(pin "D25"
		)
		(pin "D4"
		)
		(pin "D8"
		)
		(pin "N24"
		)
		(pin "AB23"
		)
		(pin "AE26"
		)
		(pin "D17"
		)
		(pin "D18"
		)
		(pin "AJ26"
		)
		(pin "AD20"
		)
		(pin "U27"
		)
		(pin "AF20"
		)
		(pin "AD23"
		)
		(pin "E9"
		)
		(pin "F19"
		)
		(pin "F29"
		)
		(pin "AA24"
		)
		(pin "AA5"
		)
		(pin "AA6"
		)
		(pin "P19"
		)
		(pin "U19"
		)
		(pin "AC27"
		)
		(pin "R25"
		)
		(pin "T24"
		)
		(pin "H30"
		)
		(pin "J17"
		)
		(pin "AK29"
		)
		(pin "V26"
		)
		(pin "V27"
		)
		(pin "F26"
		)
		(pin "F27"
		)
		(pin "AK24"
		)
		(pin "AA29"
		)
		(pin "AJ27"
		)
		(pin "K22"
		)
		(pin "A20"
		)
		(pin "A21"
		)
		(pin "AA20"
		)
		(pin "AA25"
		)
		(pin "AA26"
		)
		(pin "AA27"
		)
		(pin "AG23"
		)
		(pin "AE2"
		)
		(pin "AE22"
		)
		(pin "AF19"
		)
		(pin "Y28"
		)
		(pin "U2"
		)
		(pin "U26"
		)
		(pin "U6"
		)
		(pin "G28"
		)
		(pin "G29"
		)
		(pin "T14"
		)
		(pin "T15"
		)
		(pin "T9"
		)
		(pin "AC22"
		)
		(pin "M8"
		)
		(pin "M9"
		)
		(pin "N1"
		)
		(pin "A10"
		)
		(pin "AB1"
		)
		(pin "AB2"
		)
		(pin "D9"
		)
		(pin "E1"
		)
		(pin "E12"
		)
		(pin "V20"
		)
		(pin "AG21"
		)
		(pin "G1"
		)
		(pin "G16"
		)
		(pin "G2"
		)
		(pin "V30"
		)
		(pin "W19"
		)
		(pin "J25"
		)
		(pin "AG25"
		)
		(pin "U16"
		)
		(pin "U17"
		)
		(pin "U18"
		)
		(pin "W6"
		)
		(pin "W9"
		)
		(pin "Y17"
		)
		(pin "M12"
		)
		(pin "M13"
		)
		(pin "M14"
		)
		(pin "W16"
		)
		(pin "W17"
		)
		(pin "W18"
		)
		(pin "A3"
		)
		(pin "A4"
		)
		(pin "A7"
		)
		(pin "K6"
		)
		(pin "B3"
		)
		(pin "B7"
		)
		(pin "AD8"
		)
		(pin "AD9"
		)
		(pin "C29"
		)
		(pin "AG24"
		)
		(pin "AJ12"
		)
		(pin "AJ13"
		)
		(pin "AJ14"
		)
		(pin "AB5"
		)
		(pin "AB6"
		)
		(pin "B10"
		)
		(pin "C4"
		)
		(pin "C7"
		)
		(pin "C8"
		)
		(pin "AA17"
		)
		(pin "AA18"
		)
		(pin "AK20"
		)
		(pin "F23"
		)
		(pin "F24"
		)
		(pin "B5"
		)
		(pin "B6"
		)
		(pin "C3"
		)
		(pin "AJ17"
		)
		(pin "AJ18"
		)
		(pin "T16"
		)
		(pin "T17"
		)
		(pin "T18"
		)
		(pin "M29"
		)
		(pin "L6"
		)
		(pin "L9"
		)
		(pin "M11"
		)
		(pin "AF28"
		)
		(pin "T23"
		)
		(pin "C22"
		)
		(pin "C23"
		)
		(pin "AB27"
		)
		(pin "T26"
		)
		(pin "H25"
		)
		(pin "H26"
		)
		(pin "T2"
		)
		(pin "T5"
		)
		(pin "T6"
		)
		(pin "AH16"
		)
		(pin "AH17"
		)
		(pin "E18"
		)
		(pin "E19"
		)
		(pin "N13"
		)
		(pin "N14"
		)
		(pin "N15"
		)
		(pin "U23"
		)
		(pin "AF30"
		)
		(pin "E2"
		)
		(pin "E22"
		)
		(pin "E6"
		)
		(pin "P26"
		)
		(pin "P2"
		)
		(pin "P5"
		)
		(pin "P6"
		)
		(pin "M27"
		)
		(pin "B15"
		)
		(pin "C11"
		)
		(pin "M28"
		)
		(pin "AH22"
		)
		(pin "AA1"
		)
		(pin "AA14"
		)
		(pin "AA2"
		)
		(pin "AG30"
		)
		(pin "T27"
		)
		(pin "AE24"
		)
		(pin "U8"
		)
		(pin "V1"
		)
		(pin "C5"
		)
		(pin "D3"
		)
		(pin "D7"
		)
		(pin "AJ8"
		)
		(pin "AJ9"
		)
		(pin "C24"
		)
		(pin "C25"
		)
		(pin "AE7"
		)
		(pin "AE8"
		)
		(pin "P15"
		)
		(pin "P16"
		)
		(pin "P17"
		)
		(pin "D12"
		)
		(pin "D13"
		)
		(pin "AB10"
		)
		(pin "AB12"
		)
		(pin "AC1"
		)
		(pin "AC10"
		)
		(pin "J11"
		)
		(pin "J12"
		)
		(pin "E30"
		)
		(pin "F17"
		)
		(pin "R13"
		)
		(pin "R16"
		)
		(pin "R17"
		)
		(pin "B13"
		)
		(pin "B14"
		)
		(pin "AC5"
		)
		(pin "AC6"
		)
		(pin "AD21"
		)
		(pin "H12"
		)
		(pin "H14"
		)
		(pin "AD11"
		)
		(pin "AD12"
		)
		(pin "K17"
		)
		(pin "K27"
		)
		(pin "K4"
		)
		(pin "AE15"
		)
		(pin "AE16"
		)
		(pin "G15"
		)
		(pin "H11"
		)
		(pin "AB20"
		)
		(pin "N9"
		)
		(pin "P10"
		)
		(pin "P11"
		)
		(pin "AC23"
		)
		(pin "F4"
		)
		(pin "F8"
		)
		(pin "F9"
		)
		(pin "H20"
		)
		(pin "H21"
		)
		(pin "AK21"
		)
		(pin "G19"
		)
		(pin "G20"
		)
		(pin "V15"
		)
		(pin "V16"
		)
		(pin "V17"
		)
		(pin "L14"
		)
		(pin "L2"
		)
		(pin "L24"
		)
		(pin "L21"
		)
		(pin "B21"
		)
		(pin "B4"
		)
		(pin "B8"
		)
		(pin "F11"
		)
		(pin "F12"
		)
		(pin "A27"
		)
		(pin "A28"
		)
		(pin "L20"
		)
		(pin "AE20"
		)
		(pin "Y7"
		)
		(pin "Y8"
		)
		(pin "Y9"
		)
		(pin "AB26"
		)
		(pin "N8"
		)
		(pin "P1"
		)
		(pin "AD19"
		)
		(pin "AE14"
		)
		(pin "R24"
		)
		(pin "K23"
		)
		(pin "AD13"
		)
		(pin "AD2"
		)
		(pin "AF24"
		)
		(pin "AG28"
		)
		(pin "K30"
		)
		(pin "AA21"
		)
		(pin "J15"
		)
		(pin "J16"
		)
		(pin "AE25"
		)
		(pin "AD14"
		)
		(pin "AD16"
		)
		(pin "B18"
		)
		(pin "B19"
		)
		(pin "N30"
		)
		(pin "V28"
		)
		(pin "V29"
		)
		(pin "Y23"
		)
		(pin "AA23"
		)
		(pin "B16"
		)
		(pin "B17"
		)
		(pin "U14"
		)
		(pin "U15"
		)
		(pin "A1"
		)
		(pin "AC7"
		)
		(pin "AC9"
		)
		(pin "Y25"
		)
		(pin "AA15"
		)
		(pin "AA16"
		)
		(pin "T30"
		)
		(pin "P23"
		)
		(pin "G30"
		)
		(pin "H17"
		)
		(pin "R30"
		)
		(pin "H8"
		)
		(pin "H9"
		)
		(pin "J1"
		)
		(pin "W2"
		)
		(pin "W20"
		)
		(pin "W30"
		)
		(pin "AB15"
		)
		(pin "AB16"
		)
		(pin "R3"
		)
		(pin "R4"
		)
		(pin "R7"
		)
		(pin "E7"
		)
		(pin "E8"
		)
		(pin "F1"
		)
		(pin "Y11"
		)
		(pin "Y12"
		)
		(pin "Y13"
		)
		(pin "C17"
		)
		(pin "C19"
		)
		(pin "AG20"
		)
		(pin "AA19"
		)
		(pin "AB14"
		)
		(pin "V18"
		)
		(pin "V23"
		)
		(pin "V4"
		)
		(pin "L23"
		)
		(pin "L22"
		)
		(pin "AJ24"
		)
		(pin "AB28"
		)
		(pin "AK25"
		)
		(pin "K11"
		)
		(pin "K12"
		)
		(pin "C26"
		)
		(pin "C27"
		)
		(pin "H13"
		)
		(pin "H23"
		)
		(pin "H4"
		)
		(pin "B20"
		)
		(pin "B22"
		)
		(pin "E20"
		)
		(pin "E21"
		)
		(pin "W3"
		)
		(pin "W4"
		)
		(pin "Y1"
		)
		(pin "D6"
		)
		(pin "E3"
		)
		(pin "E4"
		)
		(pin "C12"
		)
		(pin "C13"
		)
		(pin "B27"
		)
		(pin "B28"
		)
		(pin "AH25"
		)
		(pin "N5"
		)
		(pin "P3"
		)
		(pin "P7"
		)
		(pin "U5"
		)
		(pin "V3"
		)
		(pin "V7"
		)
		(pin "C18"
		)
		(pin "C2"
		)
		(pin "C28"
		)
		(pin "AF10"
		)
		(pin "AF11"
		)
		(pin "AA7"
		)
		(pin "AB11"
		)
		(pin "AB21"
		)
		(pin "AB24"
		)
		(pin "R10"
		)
		(pin "R11"
		)
		(pin "R12"
		)
		(pin "W21"
		)
		(pin "W22"
		)
		(pin "AF2"
		)
		(pin "AF3"
		)
		(pin "AK30"
		)
		(pin "L11"
		)
		(pin "L12"
		)
		(pin "AH27"
		)
		(pin "AD17"
		)
		(pin "AD18"
		)
		(pin "A5"
		)
		(pin "A6"
		)
		(pin "A9"
		)
		(pin "M19"
		)
		(pin "G8"
		)
		(pin "H1"
		)
		(pin "H2"
		)
		(pin "U22"
		)
		(pin "AB22"
		)
		(pin "AK1"
		)
		(pin "AK10"
		)
		(pin "AK11"
		)
		(pin "G17"
		)
		(pin "G18"
		)
		(pin "AJ22"
		)
		(pin "V22"
		)
		(pin "G26"
		)
		(pin "G6"
		)
		(pin "G9"
		)
		(pin "G11"
		)
		(pin "G12"
		)
		(pin "AD22"
		)
		(pin "H5"
		)
		(pin "H6"
		)
		(pin "J3"
		)
		(pin "F25"
		)
		(pin "R23"
		)
		(pin "Y24"
		)
		(pin "AA12"
		)
		(pin "AA13"
		)
		(pin "AB8"
		)
		(pin "AB9"
		)
		(pin "Y18"
		)
		(pin "Y19"
		)
		(pin "Y15"
		)
		(pin "Y16"
		)
		(pin "AA8"
		)
		(pin "AA9"
		)
		(pin "AC3"
		)
		(pin "AC4"
		)
		(pin "AB13"
		)
		(pin "AB7"
		)
		(pin "AC11"
		)
		(pin "AC12"
		)
		(pin "L13"
		)
		(pin "L15"
		)
		(pin "AA10"
		)
		(pin "AA11"
		)
		(pin "M18"
		)
		(pin "M21"
		)
		(pin "M4"
		)
		(pin "AG12"
		)
		(pin "AG13"
		)
		(pin "P20"
		)
		(pin "W29"
		)
		(pin "R21"
		)
		(pin "AK26"
		)
		(pin "C30"
		)
		(pin "D16"
		)
		(pin "AF27"
		)
		(pin "Y29"
		)
		(pin "Y26"
		)
		(pin "AD6"
		)
		(pin "AD7"
		)
		(pin "P18"
		)
		(pin "P25"
		)
		(pin "P4"
		)
		(pin "AH7"
		)
		(pin "AH8"
		)
		(pin "AD24"
		)
		(pin "M15"
		)
		(pin "M16"
		)
		(pin "M17"
		)
		(pin "P8"
		)
		(pin "P9"
		)
		(pin "R1"
		)
		(pin "AA30"
		)
		(pin "C14"
		)
		(pin "C15"
		)
		(pin "AH30"
		)
		(pin "AB29"
		)
		(pin "M30"
		)
		(pin "W23"
		)
		(pin "W24"
		)
		(pin "A25"
		)
		(pin "A26"
		)
		(pin "A13"
		)
		(pin "A15"
		)
		(pin "L5"
		)
		(pin "M3"
		)
		(pin "M7"
		)
		(pin "AK5"
		)
		(pin "AK6"
		)
		(pin "AK8"
		)
		(pin "Y30"
		)
		(pin "AF15"
		)
		(pin "AF16"
		)
		(pin "U11"
		)
		(pin "U12"
		)
		(pin "U13"
		)
		(pin "AG7"
		)
		(pin "AG8"
		)
		(pin "M10"
		)
		(pin "R14"
		)
		(pin "R15"
		)
		(pin "P12"
		)
		(pin "P13"
		)
		(pin "P14"
		)
		(pin "R18"
		)
		(pin "R2"
		)
		(pin "R22"
		)
		(pin "N26"
		)
		(pin "AH9"
		)
		(pin "AJ1"
		)
		(pin "AJ11"
		)
		(pin "G3"
		)
		(pin "G4"
		)
		(pin "G7"
		)
		(pin "N16"
		)
		(pin "N17"
		)
		(pin "N18"
		)
		(pin "K13"
		)
		(pin "K14"
		)
		(pin "AE11"
		)
		(pin "AE13"
		)
		(pin "F28"
		)
		(pin "F30"
		)
		(pin "AK23"
		)
		(pin "F18"
		)
		(pin "F20"
		)
		(pin "N23"
		)
		(pin "T22"
		)
		(pin "AJ2"
		)
		(pin "AJ3"
		)
		(pin "AJ4"
		)
		(pin "AH4"
		)
		(pin "AH5"
		)
		(pin "AH6"
		)
		(pin "AG14"
		)
		(pin "AG15"
		)
		(pin "AH21"
		)
		(pin "L27"
		)
		(pin "AC24"
		)
		(pin "L26"
		)
		(pin "J29"
		)
		(pin "J13"
		)
		(pin "J14"
		)
		(pin "R28"
		)
		(pin "AK16"
		)
		(pin "AK18"
		)
		(pin "R5"
		)
		(pin "T3"
		)
		(pin "T7"
		)
		(pin "AE27"
		)
		(pin "AC29"
		)
		(pin "U20"
		)
		(pin "R20"
		)
		(pin "V21"
		)
		(pin "G21"
		)
		(pin "G22"
		)
		(pin "Y27"
		)
		(pin "Y3"
		)
		(pin "Y4"
		)
		(pin "D14"
		)
		(pin "E11"
		)
		(pin "U30"
		)
		(pin "L30"
		)
		(pin "E15"
		)
		(pin "E16"
		)
		(pin "N29"
		)
		(pin "M24"
		)
		(pin "AD1"
		)
		(pin "AD10"
		)
		(pin "E23"
		)
		(pin "E24"
		)
		(pin "G5"
		)
		(pin "H3"
		)
		(pin "H7"
		)
		(pin "AC15"
		)
		(pin "AC16"
		)
		(pin "F2"
		)
		(pin "F5"
		)
		(pin "F6"
		)
		(pin "AE1"
		)
		(pin "AE10"
		)
		(pin "D19"
		)
		(pin "D20"
		)
		(pin "M2"
		)
		(pin "M5"
		)
		(pin "M6"
		)
		(pin "J24"
		)
		(pin "AE21"
		)
		(pin "T20"
		)
		(pin "K18"
		)
		(pin "K19"
		)
		(pin "G25"
		)
		(pin "G27"
		)
		(pin "Y21"
		)
		(pin "C6"
		)
		(pin "C9"
		)
		(pin "D15"
		)
		(pin "R8"
		)
		(pin "T1"
		)
		(pin "D1"
		)
		(pin "D2"
		)
		(pin "D5"
		)
		(pin "F21"
		)
		(pin "F22"
		)
		(pin "V24"
		)
		(pin "V25"
		)
		(pin "AJ15"
		)
		(pin "AJ16"
		)
		(pin "U21"
		)
		(pin "AE9"
		)
		(pin "AF1"
		)
		(pin "D23"
		)
		(pin "D24"
		)
		(pin "F15"
		)
		(pin "F16"
		)
		(pin "AJ19"
		)
		(pin "AK15"
		)
		(pin "T21"
		)
		(pin "AF4"
		)
		(pin "AF5"
		)
		(pin "W25"
		)
		(pin "W26"
		)
		(pin "AJ20"
		)
		(pin "AJ30"
		)
		(pin "AK17"
		)
		(pin "AE28"
		)
		(pin "J4"
		)
		(pin "J7"
		)
		(pin "J8"
		)
		(pin "AF8"
		)
		(pin "AG1"
		)
		(pin "J23"
		)
		(pin "G13"
		)
		(pin "G14"
		)
		(pin "G23"
		)
		(pin "G24"
		)
		(pin "AK19"
		)
		(pin "B12"
		)
		(pin "B9"
		)
		(pin "C1"
		)
		(pin "C10"
		)
		(pin "AD25"
		)
		(pin "AD5"
		)
		(pin "AE12"
		)
		(pin "K28"
		)
		(pin "C20"
		)
		(pin "C21"
		)
		(pin "H29"
		)
		(pin "K24"
		)
		(pin "M25"
		)
		(pin "U29"
		)
		(pin "V19"
		)
		(pin "J22"
		)
		(pin "AC25"
		)
		(pin "J5"
		)
		(pin "K3"
		)
		(pin "K7"
		)
		(pin "J26"
		)
		(pin "T28"
		)
		(pin "U9"
		)
		(pin "V10"
		)
		(pin "V11"
		)
		(pin "AG22"
		)
		(pin "AG10"
		)
		(pin "AG11"
		)
		(pin "B30"
		)
		(pin "C16"
		)
		(pin "N25"
		)
		(pin "AD29"
		)
		(pin "K26"
		)
		(pin "AJ29"
		)
		(pin "J21"
		)
		(pin "AK28"
		)
		(pin "AE5"
		)
		(pin "AE6"
		)
		(pin "AA3"
		)
		(pin "AA4"
		)
		(pin "L3"
		)
		(pin "J27"
		)
		(pin "L16"
		)
		(pin "Y14"
		)
		(pin "E26"
		)
		(pin "E27"
		)
		(pin "A18"
		)
		(pin "A19"
		)
		(pin "AF25"
		)
		(pin "N27"
		)
		(pin "AB30"
		)
		(pin "Y22"
		)
		(pin "AG19"
		)
		(pin "AH15"
		)
		(pin "AG17"
		)
		(pin "AG18"
		)
		(pin "Y20"
		)
		(pin "AF12"
		)
		(pin "AF13"
		)
		(pin "K15"
		)
		(pin "K16"
		)
		(pin "P27"
		)
		(pin "L25"
		)
		(pin "L4"
		)
		(pin "L7"
		)
		(pin "AJ5"
		)
		(pin "AJ6"
		)
		(pin "AJ7"
		)
		(pin "AD30"
		)
		(pin "AE29"
		)
		(pin "AC21"
		)
		(pin "AH10"
		)
		(pin "AH11"
		)
		(pin "AH12"
		)
		(pin "N21"
		)
		(pin "AH24"
		)
		(pin "AG29"
		)
		(pin "P24"
		)
		(pin "AD3"
		)
		(pin "AD4"
		)
		(pin "A29"
		)
		(pin "A30"
		)
		(pin "R26"
		)
		(pin "V8"
		)
		(pin "V9"
		)
		(pin "W1"
		)
		(pin "U3"
		)
		(pin "U4"
		)
		(pin "U7"
		)
		(pin "U24"
		)
		(pin "T19"
		)
		(pin "T29"
		)
		(pin "T4"
		)
		(pin "H18"
		)
		(pin "H19"
		)
		(pin "W13"
		)
		(pin "W14"
		)
		(pin "W15"
		)
		(pin "F13"
		)
		(pin "F14"
		)
		(pin "AE3"
		)
		(pin "AE4"
		)
		(pin "D21"
		)
		(pin "D22"
		)
		(pin "AG4"
		)
		(pin "AG5"
		)
		(pin "AG9"
		)
		(pin "AH1"
		)
		(instances
			(project "k410t-devboard"
				(path ""
					(reference "U1")
					(unit 7)
				)
			)
		)
	)
)
